FILE_TYPE = CONNECTIVITY;
{Allegro Design Entry HDL 16.6-p007 (v16-6-112F) 10/10/2012}
"PAGE_NUMBER" = 59;
0"NC";
1"M_J_DQS_DP<17:0>";
2"M_J_DQS_DN<17:0>";
3"M_J_MA<17:0>";
4"M_J_BA<1:0>";
5"M_J_BG<1:0>";
6"M_J_CKE <3:0>";
7"M_J_CS_N<7:0>";
8"M_J_ODT<3:0>";
9"M_J_DQ<63:0>";
10"M_J_CLK_DN<3:0>";
11"M_J_CLK_DP<3:0>";
12"M_J_ECC<7:0>";
13"M_J_DQS_DN<8>";
14"M_J_DQ<55>";
15"M_J_DQ<41>";
16"M_J_DQ<53>";
17"M_J_ODT<3>";
18"M_J_DQ<35>";
19"M_J_DQ<33>";
20"M_J_C<2>";
21"M_J_ECC<0>";
22"M_J_ECC<1>";
23"M_J_ECC<2>";
24"M_J_ECC<3>";
25"M_J_ECC<4>";
26"M_J_ECC<5>";
27"M_J_ECC<6>";
28"M_J_ECC<7>";
29"M_J_DQ<0>";
30"M_J_DQ<1>";
31"M_J_DQ<2>";
32"M_J_DQ<3>";
33"M_J_DQ<4>";
34"M_J_DQ<5>";
35"M_J_DQ<6>";
36"M_J_DQ<7>";
37"M_J_DQ<8>";
38"M_J_DQ<9>";
39"M_J_DQ<10>";
40"M_J_CLK_DP<0>";
41"M_J_CLK_DP<1>";
42"M_J_CLK_DP<2>";
43"M_J_CLK_DP<3>";
44"M_J_CLK_DN<0>";
45"M_J_CLK_DN<1>";
46"M_J_CLK_DN<2>";
47"M_J_CLK_DN<3>";
48"M_J_DQ<11>";
49"M_J_DQ<12>";
50"M_J_DQ<13>";
51"M_J_DQ<14>";
52"M_J_DQ<15>";
53"M_J_DQ<16>";
54"M_J_DQ<17>";
55"M_J_DQ<18>";
56"M_J_DQ<19>";
57"M_J_DQ<20>";
58"M_J_DQ<21>";
59"M_J_DQ<22>";
60"M_J_DQ<23>";
61"M_J_DQ<24>";
62"M_J_DQ<25>";
63"M_J_DQ<26>";
64"M_J_DQ<27>";
65"M_J_DQ<28>";
66"M_J_DQ<29>";
67"M_J_DQ<30>";
68"M_J_DQ<31>";
69"M_J_DQ<32>";
70"M_J_DQ<34>";
71"M_J_DQ<36>";
72"M_J_DQ<37>";
73"M_J_DQ<38>";
74"M_J_DQ<39>";
75"M_J_DQ<40>";
76"M_J_DQ<42>";
77"M_J_DQ<43>";
78"M_J_DQ<44>";
79"M_J_DQ<45>";
80"M_J_DQ<46>";
81"M_J_DQ<47>";
82"M_J_DQ<48>";
83"M_J_DQ<49>";
84"M_J_DQ<50>";
85"M_J_DQ<51>";
86"M_J_DQ<52>";
87"M_J_DQ<54>";
88"M_J_DQ<56>";
89"M_J_DQ<57>";
90"M_J_DQ<58>";
91"M_J_DQ<59>";
92"M_J_DQ<60>";
93"M_J_DQ<61>";
94"M_J_DQ<62>";
95"M_J_DQ<63>";
96"M_J_ODT<0>";
97"M_J_ODT<1>";
98"M_J_ODT<2>";
99"M_J_MA<0>";
100"M_J_MA<1>";
101"M_J_MA<2>";
102"M_J_CS_N<0>";
103"M_J_CS_N<1>";
104"M_J_CS_N<2>";
105"M_J_CS_N<3>";
106"M_J_CS_N<4>";
107"M_J_CS_N<5>";
108"M_J_CS_N<6>";
109"M_J_CS_N<7>";
110"M_J_CKE <0>";
111"M_J_CKE <1>";
112"M_J_CKE <2>";
113"M_J_CKE <3>";
114"M_J_BG<0>";
115"M_J_BG<1>";
116"M_J_BA<0>";
117"M_J_BA<1>";
118"M_J_MA<3>";
119"M_J_MA<4>";
120"M_J_MA<5>";
121"M_J_MA<6>";
122"M_J_MA<7>";
123"M_J_MA<8>";
124"M_J_MA<9>";
125"M_J_MA<10>";
126"M_J_MA<11>";
127"M_J_MA<12>";
128"M_J_MA<13>";
129"M_J_MA<14>";
130"M_J_MA<15>";
131"M_J_MA<16>";
132"M_J_MA<17>";
133"M_J_DQS_DP<0>";
134"M_J_DQS_DP<1>";
135"M_J_DQS_DP<2>";
136"M_J_DQS_DP<3>";
137"M_J_DQS_DP<4>";
138"M_J_DQS_DP<5>";
139"M_J_DQS_DN<0>";
140"M_J_DQS_DN<1>";
141"M_J_DQS_DN<2>";
142"M_J_DQS_DN<3>";
143"M_J_DQS_DN<4>";
144"M_J_DQS_DN<5>";
145"M_J_DQS_DN<6>";
146"M_J_DQS_DN<7>";
147"M_J_DQS_DN<9>";
148"M_J_DQS_DN<10>";
149"M_J_DQS_DN<11>";
150"M_J_DQS_DN<12>";
151"M_J_DQS_DN<13>";
152"M_J_DQS_DN<14>";
153"M_J_DQS_DN<15>";
154"M_J_DQS_DN<16>";
155"M_J_DQS_DN<17>";
156"M_J_PAR";
157"M_J_ALERT_N";
158"M_J_ACT_N";
159"M_J_DQS_DP<6>";
160"M_J_DQS_DP<7>";
161"M_J_DQS_DP<8>";
162"M_J_DQS_DP<9>";
163"M_J_DQS_DP<10>";
164"M_J_DQS_DP<11>";
165"M_J_DQS_DP<12>";
166"M_J_DQS_DP<13>";
167"M_J_DQS_DP<14>";
168"M_J_DQS_DP<15>";
169"M_J_DQS_DP<16>";
170"M_J_DQS_DP<17>";
%"TAP"
"6","(-5575,800)","0","mstr_standard","I10";
;
CDS_LIB"mstr_standard"
BODY_TYPE"PLUMBING"
HDL_TAP"TRUE";
"B \NAC \NWC"11;
"S \NAC"
BN"0"40;
%"TAP"
"6","(-2850,1550)","2","mstr_standard","I100";
;
CDS_LIB"mstr_standard"
BODY_TYPE"PLUMBING"
HDL_TAP"TRUE";
"B \NAC \NWC"8;
"S \NAC"
BN"3"17;
%"TAP"
"6","(-2850,1500)","2","mstr_standard","I101";
;
CDS_LIB"mstr_standard"
BODY_TYPE"PLUMBING"
HDL_TAP"TRUE";
"B \NAC \NWC"8;
"S \NAC"
BN"2"98;
%"TAP"
"6","(-2850,1450)","2","mstr_standard","I102";
;
CDS_LIB"mstr_standard"
BODY_TYPE"PLUMBING"
HDL_TAP"TRUE";
"B \NAC \NWC"8;
"S \NAC"
BN"1"97;
%"TAP"
"6","(-2850,1650)","2","mstr_standard","I103";
;
CDS_LIB"mstr_standard"
BODY_TYPE"PLUMBING"
HDL_TAP"TRUE";
"B \NAC \NWC"6;
"S \NAC"
BN"0"110;
%"TAP"
"6","(-2850,1700)","2","mstr_standard","I104";
;
CDS_LIB"mstr_standard"
BODY_TYPE"PLUMBING"
HDL_TAP"TRUE";
"B \NAC \NWC"6;
"S \NAC"
BN"1"111;
%"TAP"
"6","(-2850,1750)","2","mstr_standard","I105";
;
CDS_LIB"mstr_standard"
BODY_TYPE"PLUMBING"
HDL_TAP"TRUE";
"B \NAC \NWC"6;
"S \NAC"
BN"2"112;
%"TAP"
"6","(-2850,1800)","2","mstr_standard","I106";
;
CDS_LIB"mstr_standard"
BODY_TYPE"PLUMBING"
HDL_TAP"TRUE";
"B \NAC \NWC"6;
"S \NAC"
BN"3"113;
%"TAP"
"6","(-2850,1900)","2","mstr_standard","I107";
;
CDS_LIB"mstr_standard"
BODY_TYPE"PLUMBING"
HDL_TAP"TRUE";
"B \NAC \NWC"3;
"S \NAC"
BN"0"99;
%"TAP"
"6","(-2850,1950)","2","mstr_standard","I108";
;
CDS_LIB"mstr_standard"
BODY_TYPE"PLUMBING"
HDL_TAP"TRUE";
"B \NAC \NWC"3;
"S \NAC"
BN"1"100;
%"TAP"
"6","(-2850,2050)","2","mstr_standard","I109";
;
CDS_LIB"mstr_standard"
BODY_TYPE"PLUMBING"
HDL_TAP"TRUE";
"B \NAC \NWC"3;
"S \NAC"
BN"3"118;
%"TAP"
"6","(-5575,900)","0","mstr_standard","I11";
;
CDS_LIB"mstr_standard"
BODY_TYPE"PLUMBING"
HDL_TAP"TRUE";
"B \NAC \NWC"11;
"S \NAC"
BN"2"42;
%"TAP"
"6","(-2850,2000)","2","mstr_standard","I110";
;
CDS_LIB"mstr_standard"
BODY_TYPE"PLUMBING"
HDL_TAP"TRUE";
"B \NAC \NWC"3;
"S \NAC"
BN"2"101;
%"TAP"
"6","(-2850,2100)","2","mstr_standard","I111";
;
CDS_LIB"mstr_standard"
BODY_TYPE"PLUMBING"
HDL_TAP"TRUE";
"B \NAC \NWC"3;
"S \NAC"
BN"4"119;
%"TAP"
"6","(-2850,2150)","2","mstr_standard","I112";
;
CDS_LIB"mstr_standard"
BODY_TYPE"PLUMBING"
HDL_TAP"TRUE";
"B \NAC \NWC"3;
"S \NAC"
BN"5"120;
%"TAP"
"6","(-2850,2200)","2","mstr_standard","I113";
;
CDS_LIB"mstr_standard"
BODY_TYPE"PLUMBING"
HDL_TAP"TRUE";
"B \NAC \NWC"3;
"S \NAC"
BN"6"121;
%"TAP"
"6","(-2850,2300)","2","mstr_standard","I114";
;
CDS_LIB"mstr_standard"
BODY_TYPE"PLUMBING"
HDL_TAP"TRUE";
"B \NAC \NWC"3;
"S \NAC"
BN"8"123;
%"TAP"
"6","(-2850,2250)","2","mstr_standard","I115";
;
CDS_LIB"mstr_standard"
BODY_TYPE"PLUMBING"
HDL_TAP"TRUE";
"B \NAC \NWC"3;
"S \NAC"
BN"7"122;
%"TAP"
"6","(-2850,2450)","2","mstr_standard","I116";
;
CDS_LIB"mstr_standard"
BODY_TYPE"PLUMBING"
HDL_TAP"TRUE";
"B \NAC \NWC"3;
"S \NAC"
BN"11"126;
%"TAP"
"6","(-2850,2400)","2","mstr_standard","I117";
;
CDS_LIB"mstr_standard"
BODY_TYPE"PLUMBING"
HDL_TAP"TRUE";
"B \NAC \NWC"3;
"S \NAC"
BN"10"125;
%"TAP"
"6","(-2850,2350)","2","mstr_standard","I118";
;
CDS_LIB"mstr_standard"
BODY_TYPE"PLUMBING"
HDL_TAP"TRUE";
"B \NAC \NWC"3;
"S \NAC"
BN"9"124;
%"TAP"
"6","(-2850,2500)","2","mstr_standard","I119";
;
CDS_LIB"mstr_standard"
BODY_TYPE"PLUMBING"
HDL_TAP"TRUE";
"B \NAC \NWC"3;
"S \NAC"
BN"12"127;
%"TAP"
"6","(-5575,950)","0","mstr_standard","I12";
;
CDS_LIB"mstr_standard"
BODY_TYPE"PLUMBING"
HDL_TAP"TRUE";
"B \NAC \NWC"11;
"S \NAC"
BN"3"43;
%"TAP"
"6","(-2850,2550)","2","mstr_standard","I120";
;
CDS_LIB"mstr_standard"
BODY_TYPE"PLUMBING"
HDL_TAP"TRUE";
"B \NAC \NWC"3;
"S \NAC"
BN"13"128;
%"TAP"
"6","(-2850,2600)","2","mstr_standard","I121";
;
CDS_LIB"mstr_standard"
BODY_TYPE"PLUMBING"
HDL_TAP"TRUE";
"B \NAC \NWC"3;
"S \NAC"
BN"14"129;
%"TAP"
"6","(-2850,2650)","2","mstr_standard","I122";
;
CDS_LIB"mstr_standard"
BODY_TYPE"PLUMBING"
HDL_TAP"TRUE";
"B \NAC \NWC"3;
"S \NAC"
BN"15"130;
%"TAP"
"6","(-2850,2700)","2","mstr_standard","I123";
;
CDS_LIB"mstr_standard"
BODY_TYPE"PLUMBING"
HDL_TAP"TRUE";
"B \NAC \NWC"3;
"S \NAC"
BN"16"131;
%"TAP"
"6","(-2850,2750)","2","mstr_standard","I124";
;
CDS_LIB"mstr_standard"
BODY_TYPE"PLUMBING"
HDL_TAP"TRUE";
"B \NAC \NWC"3;
"S \NAC"
BN"17"132;
%"TAP"
"6","(-2850,2900)","2","mstr_standard","I125";
;
CDS_LIB"mstr_standard"
BODY_TYPE"PLUMBING"
HDL_TAP"TRUE";
"B \NAC \NWC"2;
"S \NAC"
BN"1"140;
%"TAP"
"6","(-2850,2950)","2","mstr_standard","I126";
;
CDS_LIB"mstr_standard"
BODY_TYPE"PLUMBING"
HDL_TAP"TRUE";
"B \NAC \NWC"2;
"S \NAC"
BN"2"141;
%"TAP"
"6","(-2850,2850)","2","mstr_standard","I127";
;
CDS_LIB"mstr_standard"
BODY_TYPE"PLUMBING"
HDL_TAP"TRUE";
"B \NAC \NWC"2;
"S \NAC"
BN"0"139;
%"TAP"
"6","(-2850,3050)","2","mstr_standard","I128";
;
CDS_LIB"mstr_standard"
BODY_TYPE"PLUMBING"
HDL_TAP"TRUE";
"B \NAC \NWC"2;
"S \NAC"
BN"4"143;
%"TAP"
"6","(-2850,3000)","2","mstr_standard","I129";
;
CDS_LIB"mstr_standard"
BODY_TYPE"PLUMBING"
HDL_TAP"TRUE";
"B \NAC \NWC"2;
"S \NAC"
BN"3"142;
%"TAP"
"6","(-5575,1050)","0","mstr_standard","I13";
;
CDS_LIB"mstr_standard"
BODY_TYPE"PLUMBING"
HDL_TAP"TRUE";
"B \NAC \NWC"12;
"S \NAC"
BN"0"21;
%"TAP"
"6","(-2850,3100)","2","mstr_standard","I130";
;
CDS_LIB"mstr_standard"
BODY_TYPE"PLUMBING"
HDL_TAP"TRUE";
"B \NAC \NWC"2;
"S \NAC"
BN"5"144;
%"TAP"
"6","(-2850,3150)","2","mstr_standard","I131";
;
CDS_LIB"mstr_standard"
BODY_TYPE"PLUMBING"
HDL_TAP"TRUE";
"B \NAC \NWC"2;
"S \NAC"
BN"6"145;
%"TAP"
"6","(-2850,3200)","2","mstr_standard","I132";
;
CDS_LIB"mstr_standard"
BODY_TYPE"PLUMBING"
HDL_TAP"TRUE";
"B \NAC \NWC"2;
"S \NAC"
BN"7"146;
%"TAP"
"6","(-2850,3250)","2","mstr_standard","I133";
;
CDS_LIB"mstr_standard"
BODY_TYPE"PLUMBING"
HDL_TAP"TRUE";
"B \NAC \NWC"2;
"S \NAC"
BN"8"13;
%"TAP"
"6","(-2850,3300)","2","mstr_standard","I134";
;
CDS_LIB"mstr_standard"
BODY_TYPE"PLUMBING"
HDL_TAP"TRUE";
"B \NAC \NWC"2;
"S \NAC"
BN"9"147;
%"TAP"
"6","(-2850,3350)","2","mstr_standard","I135";
;
CDS_LIB"mstr_standard"
BODY_TYPE"PLUMBING"
HDL_TAP"TRUE";
"B \NAC \NWC"2;
"S \NAC"
BN"10"148;
%"TAP"
"6","(-2850,3450)","2","mstr_standard","I136";
;
CDS_LIB"mstr_standard"
BODY_TYPE"PLUMBING"
HDL_TAP"TRUE";
"B \NAC \NWC"2;
"S \NAC"
BN"12"150;
%"TAP"
"6","(-2850,3400)","2","mstr_standard","I137";
;
CDS_LIB"mstr_standard"
BODY_TYPE"PLUMBING"
HDL_TAP"TRUE";
"B \NAC \NWC"2;
"S \NAC"
BN"11"149;
%"TAP"
"6","(-2850,3600)","2","mstr_standard","I138";
;
CDS_LIB"mstr_standard"
BODY_TYPE"PLUMBING"
HDL_TAP"TRUE";
"B \NAC \NWC"2;
"S \NAC"
BN"15"153;
%"TAP"
"6","(-2850,3550)","2","mstr_standard","I139";
;
CDS_LIB"mstr_standard"
BODY_TYPE"PLUMBING"
HDL_TAP"TRUE";
"B \NAC \NWC"2;
"S \NAC"
BN"14"152;
%"TAP"
"6","(-5575,1100)","0","mstr_standard","I14";
;
CDS_LIB"mstr_standard"
BODY_TYPE"PLUMBING"
HDL_TAP"TRUE";
"B \NAC \NWC"12;
"S \NAC"
BN"1"22;
%"TAP"
"6","(-2850,3500)","2","mstr_standard","I140";
;
CDS_LIB"mstr_standard"
BODY_TYPE"PLUMBING"
HDL_TAP"TRUE";
"B \NAC \NWC"2;
"S \NAC"
BN"13"151;
%"TAP"
"6","(-2850,3650)","2","mstr_standard","I141";
;
CDS_LIB"mstr_standard"
BODY_TYPE"PLUMBING"
HDL_TAP"TRUE";
"B \NAC \NWC"2;
"S \NAC"
BN"16"154;
%"TAP"
"6","(-2850,3700)","2","mstr_standard","I142";
;
CDS_LIB"mstr_standard"
BODY_TYPE"PLUMBING"
HDL_TAP"TRUE";
"B \NAC \NWC"2;
"S \NAC"
BN"17"155;
%"TAP"
"6","(-2850,3800)","2","mstr_standard","I143";
;
CDS_LIB"mstr_standard"
BODY_TYPE"PLUMBING"
HDL_TAP"TRUE";
"B \NAC \NWC"1;
"S \NAC"
BN"0"133;
%"TAP"
"6","(-2850,3850)","2","mstr_standard","I144";
;
CDS_LIB"mstr_standard"
BODY_TYPE"PLUMBING"
HDL_TAP"TRUE";
"B \NAC \NWC"1;
"S \NAC"
BN"1"134;
%"TAP"
"6","(-2850,3900)","2","mstr_standard","I145";
;
CDS_LIB"mstr_standard"
BODY_TYPE"PLUMBING"
HDL_TAP"TRUE";
"B \NAC \NWC"1;
"S \NAC"
BN"2"135;
%"TAP"
"6","(-2850,3950)","2","mstr_standard","I146";
;
CDS_LIB"mstr_standard"
BODY_TYPE"PLUMBING"
HDL_TAP"TRUE";
"B \NAC \NWC"1;
"S \NAC"
BN"3"136;
%"TAP"
"6","(-5575,1150)","0","mstr_standard","I15";
;
CDS_LIB"mstr_standard"
BODY_TYPE"PLUMBING"
HDL_TAP"TRUE";
"B \NAC \NWC"12;
"S \NAC"
BN"2"23;
%"TAP"
"6","(-2850,4000)","2","mstr_standard","I157";
;
CDS_LIB"mstr_standard"
BODY_TYPE"PLUMBING"
HDL_TAP"TRUE";
"B \NAC \NWC"1;
"S \NAC"
BN"4"137;
%"TAP"
"6","(-2850,4100)","2","mstr_standard","I158";
;
CDS_LIB"mstr_standard"
BODY_TYPE"PLUMBING"
HDL_TAP"TRUE";
"B \NAC \NWC"1;
"S \NAC"
BN"6"159;
%"TAP"
"6","(-2850,4050)","2","mstr_standard","I159";
;
CDS_LIB"mstr_standard"
BODY_TYPE"PLUMBING"
HDL_TAP"TRUE";
"B \NAC \NWC"1;
"S \NAC"
BN"5"138;
%"TAP"
"6","(-5575,1250)","0","mstr_standard","I16";
;
CDS_LIB"mstr_standard"
BODY_TYPE"PLUMBING"
HDL_TAP"TRUE";
"B \NAC \NWC"12;
"S \NAC"
BN"4"25;
%"TAP"
"6","(-2850,4150)","2","mstr_standard","I160";
;
CDS_LIB"mstr_standard"
BODY_TYPE"PLUMBING"
HDL_TAP"TRUE";
"B \NAC \NWC"1;
"S \NAC"
BN"7"160;
%"TAP"
"6","(-2850,4200)","2","mstr_standard","I161";
;
CDS_LIB"mstr_standard"
BODY_TYPE"PLUMBING"
HDL_TAP"TRUE";
"B \NAC \NWC"1;
"S \NAC"
BN"8"161;
%"TAP"
"6","(-2850,4250)","2","mstr_standard","I162";
;
CDS_LIB"mstr_standard"
BODY_TYPE"PLUMBING"
HDL_TAP"TRUE";
"B \NAC \NWC"1;
"S \NAC"
BN"9"162;
%"TAP"
"6","(-2850,4300)","2","mstr_standard","I163";
;
CDS_LIB"mstr_standard"
BODY_TYPE"PLUMBING"
HDL_TAP"TRUE";
"B \NAC \NWC"1;
"S \NAC"
BN"10"163;
%"TAP"
"6","(-2850,4350)","2","mstr_standard","I164";
;
CDS_LIB"mstr_standard"
BODY_TYPE"PLUMBING"
HDL_TAP"TRUE";
"B \NAC \NWC"1;
"S \NAC"
BN"11"164;
%"TAP"
"6","(-2850,4500)","2","mstr_standard","I165";
;
CDS_LIB"mstr_standard"
BODY_TYPE"PLUMBING"
HDL_TAP"TRUE";
"B \NAC \NWC"1;
"S \NAC"
BN"14"167;
%"TAP"
"6","(-2850,4450)","2","mstr_standard","I166";
;
CDS_LIB"mstr_standard"
BODY_TYPE"PLUMBING"
HDL_TAP"TRUE";
"B \NAC \NWC"1;
"S \NAC"
BN"13"166;
%"TAP"
"6","(-2850,4400)","2","mstr_standard","I167";
;
CDS_LIB"mstr_standard"
BODY_TYPE"PLUMBING"
HDL_TAP"TRUE";
"B \NAC \NWC"1;
"S \NAC"
BN"12"165;
%"TAP"
"6","(-2850,4550)","2","mstr_standard","I168";
;
CDS_LIB"mstr_standard"
BODY_TYPE"PLUMBING"
HDL_TAP"TRUE";
"B \NAC \NWC"1;
"S \NAC"
BN"15"168;
%"TAP"
"6","(-2850,4600)","2","mstr_standard","I169";
;
CDS_LIB"mstr_standard"
BODY_TYPE"PLUMBING"
HDL_TAP"TRUE";
"B \NAC \NWC"1;
"S \NAC"
BN"16"169;
%"TAP"
"6","(-5575,1200)","0","mstr_standard","I17";
;
CDS_LIB"mstr_standard"
BODY_TYPE"PLUMBING"
HDL_TAP"TRUE";
"B \NAC \NWC"12;
"S \NAC"
BN"3"24;
%"TAP"
"6","(-2850,4650)","2","mstr_standard","I170";
;
CDS_LIB"mstr_standard"
BODY_TYPE"PLUMBING"
HDL_TAP"TRUE";
"B \NAC \NWC"1;
"S \NAC"
BN"17"170;
%"SKX_EXT_B"
"5","(-4175,2550)","0","chpset_lib","I172";
;
CDS_SEC"5"
LOCATION"U2D1"
PART_NUMBER"TBD"
MATERIAL"IC"
PACK_TYPE"BGA1"
SEC_TYPE"BGA1"
CDS_LIB"chpset_lib"
SEC"5"
CDS_LOCATION"U2D1";
"DDR2_PAR"
$PN"V53"156;
"DDR2_ODT<0>"
$PN"AA50"96;
"DDR2_ODT<1>"
$PN"AA48"97;
"DDR2_ODT<2>"
$PN"V49"98;
"DDR2_ODT<3>"
$PN"AB47"17;
"DDR2_MA<0>"
$PN"AB53"99;
"DDR2_MA<1>"
$PN"AE58"100;
"DDR2_MA<2>"
$PN"AD57"101;
"DDR2_MA<3>"
$PN"W58"118;
"DDR2_MA<4>"
$PN"AA58"119;
"DDR2_MA<5>"
$PN"V59"120;
"DDR2_MA<6>"
$PN"AB59"121;
"DDR2_MA<7>"
$PN"AE60"122;
"DDR2_MA<8>"
$PN"AD59"123;
"DDR2_MA<9>"
$PN"AG58"124;
"DDR2_MA<10>"
$PN"AD55"125;
"DDR2_MA<11>"
$PN"AG60"126;
"DDR2_MA<12>"
$PN"AG62"127;
"DDR2_MA<13>"
$PN"AD53"128;
"DDR2_MA<14>"
$PN"W50"129;
"DDR2_MA<15>"
$PN"AE54"130;
"DDR2_MA<16>"
$PN"AA52"131;
"DDR2_MA<17>"
$PN"AC46"132;
"DDR2_ECC<0>"
$PN"AU72"21;
"DDR2_ECC<1>"
$PN"BA72"22;
"DDR2_ECC<2>"
$PN"AV69"23;
"DDR2_ECC<3>"
$PN"AY69"24;
"DDR2_ECC<4>"
$PN"AV73"25;
"DDR2_ECC<5>"
$PN"AY73"26;
"DDR2_ECC<6>"
$PN"AU70"27;
"DDR2_ECC<7>"
$PN"BA70"28;
"DDR2_DQS_DP<0>"
$PN"AM75"133;
"DDR2_DQS_DP<1>"
$PN"AB75"134;
"DDR2_DQS_DP<2>"
$PN"W70"135;
"DDR2_DQS_DP<3>"
$PN"AR66"136;
"DDR2_DQS_DP<4>"
$PN"Y39"137;
"DDR2_DQS_DP<5>"
$PN"Y33"138;
"DDR2_DQS_DP<6>"
$PN"AG30"159;
"DDR2_DQS_DP<7>"
$PN"AG24"160;
"DDR2_DQS_DP<8>"
$PN"AY71"161;
"DDR2_DQS_DP<9>"
$PN"AN76"162;
"DDR2_DQS_DP<10>"
$PN"AC76"163;
"DDR2_DQS_DP<11>"
$PN"V71"164;
"DDR2_DQS_DP<12>"
$PN"AN66"165;
"DDR2_DQS_DP<13>"
$PN"V39"166;
"DDR2_DQS_DP<14>"
$PN"V33"167;
"DDR2_DQS_DP<15>"
$PN"AE30"168;
"DDR2_DQS_DP<16>"
$PN"AE24"169;
"DDR2_DQS_DP<17>"
$PN"AV71"170;
"DDR2_DQS_DN<0>"
$PN"AL74"139;
"DDR2_DQS_DN<1>"
$PN"AA74"140;
"DDR2_DQS_DN<2>"
$PN"Y69"141;
"DDR2_DQS_DN<3>"
$PN"AU66"142;
"DDR2_DQS_DN<4>"
$PN"AB39"143;
"DDR2_DQS_DN<5>"
$PN"AB33"144;
"DDR2_DQS_DN<6>"
$PN"AJ30"145;
"DDR2_DQS_DN<7>"
$PN"AJ24"146;
"DDR2_DQS_DN<8>"
$PN"BB71"13;
"DDR2_DQS_DN<9>"
$PN"AP77"147;
"DDR2_DQS_DN<10>"
$PN"AD77"148;
"DDR2_DQS_DN<11>"
$PN"U72"149;
"DDR2_DQS_DN<12>"
$PN"AL66"150;
"DDR2_DQS_DN<13>"
$PN"T39"151;
"DDR2_DQS_DN<14>"
$PN"T33"152;
"DDR2_DQS_DN<15>"
$PN"AC30"153;
"DDR2_DQS_DN<16>"
$PN"AC24"154;
"DDR2_DQS_DN<17>"
$PN"AT71"155;
"DDR2_DQ<0>"
$PN"AR76"29;
"DDR2_DQ<1>"
$PN"AN74"30;
"DDR2_DQ<2>"
$PN"AK77"31;
"DDR2_DQ<3>"
$PN"AJ76"32;
"DDR2_DQ<4>"
$PN"AT75"33;
"DDR2_DQ<5>"
$PN"AR74"34;
"DDR2_DQ<6>"
$PN"AM77"35;
"DDR2_DQ<7>"
$PN"AK75"36;
"DDR2_DQ<8>"
$PN"AE76"37;
"DDR2_DQ<9>"
$PN"AC74"38;
"DDR2_DQ<10>"
$PN"Y77"39;
"DDR2_DQ<11>"
$PN"W76"48;
"DDR2_DQ<12>"
$PN"AF75"49;
"DDR2_DQ<13>"
$PN"AE74"50;
"DDR2_DQ<14>"
$PN"AB77"51;
"DDR2_DQ<15>"
$PN"Y75"52;
"DDR2_DQ<16>"
$PN"W72"53;
"DDR2_DQ<17>"
$PN"AA70"54;
"DDR2_DQ<18>"
$PN"R70"55;
"DDR2_DQ<19>"
$PN"T69"56;
"DDR2_DQ<20>"
$PN"AA72"57;
"DDR2_DQ<21>"
$PN"AB71"58;
"DDR2_DQ<22>"
$PN"T71"59;
"DDR2_DQ<23>"
$PN"V69"60;
"DDR2_DQ<24>"
$PN"AM67"61;
"DDR2_DQ<25>"
$PN"AT67"62;
"DDR2_DQ<26>"
$PN"AN64"63;
"DDR2_DQ<27>"
$PN"AR64"64;
"DDR2_DQ<28>"
$PN"AN68"65;
"DDR2_DQ<29>"
$PN"AR68"66;
"DDR2_DQ<30>"
$PN"AM65"67;
"DDR2_DQ<31>"
$PN"AT65"68;
"DDR2_DQ<32>"
$PN"U40"69;
"DDR2_DQ<33>"
$PN"AA40"19;
"DDR2_DQ<34>"
$PN"V37"70;
"DDR2_DQ<35>"
$PN"Y37"18;
"DDR2_DQ<36>"
$PN"V41"71;
"DDR2_DQ<37>"
$PN"Y41"72;
"DDR2_DQ<38>"
$PN"U38"73;
"DDR2_DQ<39>"
$PN"AA38"74;
"DDR2_DQ<40>"
$PN"U34"75;
"DDR2_DQ<41>"
$PN"AA34"15;
"DDR2_DQ<42>"
$PN"V31"76;
"DDR2_DQ<43>"
$PN"Y31"77;
"DDR2_DQ<44>"
$PN"V35"78;
"DDR2_DQ<45>"
$PN"Y35"79;
"DDR2_DQ<46>"
$PN"U32"80;
"DDR2_DQ<47>"
$PN"AA32"81;
"DDR2_DQ<48>"
$PN"AD31"82;
"DDR2_DQ<49>"
$PN"AH31"83;
"DDR2_DQ<50>"
$PN"AE28"84;
"DDR2_DQ<51>"
$PN"AG28"85;
"DDR2_DQ<52>"
$PN"AE32"86;
"DDR2_DQ<53>"
$PN"AG32"16;
"DDR2_DQ<54>"
$PN"AD29"87;
"DDR2_DQ<55>"
$PN"AH29"14;
"DDR2_DQ<56>"
$PN"AD25"88;
"DDR2_DQ<57>"
$PN"AH25"89;
"DDR2_DQ<58>"
$PN"AE22"90;
"DDR2_DQ<59>"
$PN"AG22"91;
"DDR2_DQ<60>"
$PN"AE26"92;
"DDR2_DQ<61>"
$PN"AG26"93;
"DDR2_DQ<62>"
$PN"AD23"94;
"DDR2_DQ<63>"
$PN"AH23"95;
"DDR2_CS_N<0>"
$PN"V51"102;
"DDR2_CS_N<1>"
$PN"AB49"103;
"DDR2_CS_N<2>"
$PN"W46"104;
"DDR2_CS_N<3>"
$PN"AA46"105;
"DDR2_CS_N<4>"
$PN"AB51"106;
"DDR2_CS_N<5>"
$PN"W48"107;
"DDR2_CS_N<6>"
$PN"T45"108;
"DDR2_CS_N<7>"
$PN"V45"109;
"DDR2_CLK_DP<0>"
$PN"AB55"40;
"DDR2_CLK_DP<1>"
$PN"V55"41;
"DDR2_CLK_DP<2>"
$PN"AB57"42;
"DDR2_CLK_DP<3>"
$PN"V57"43;
"DDR2_CLK_DN<0>"
$PN"AA54"44;
"DDR2_CLK_DN<1>"
$PN"W54"45;
"DDR2_CLK_DN<2>"
$PN"AA56"46;
"DDR2_CLK_DN<3>"
$PN"W56"47;
"DDR2_CKE<0>"
$PN"AA62"110;
"DDR2_CKE<1>"
$PN"AD63"111;
"DDR2_CKE<2>"
$PN"V63"112;
"DDR2_CKE<3>"
$PN"AB63"113;
"DDR2_CID<2>"
$PN"AB45"20;
"DDR2_BG<0>"
$PN"AA60"114;
"DDR2_BG<1>"
$PN"AE62"115;
"DDR2_BA<0>"
$PN"W52"116;
"DDR2_BA<1>"
$PN"AE56"117;
"DDR2_ALERT_N"
$PN"AD61"157;
"DDR2_ACT_N"
$PN"AB61"158;
%"TAP"
"6","(-5575,1300)","0","mstr_standard","I18";
;
CDS_LIB"mstr_standard"
BODY_TYPE"PLUMBING"
HDL_TAP"TRUE";
"B \NAC \NWC"12;
"S \NAC"
BN"5"26;
%"TAP"
"6","(-5575,1350)","0","mstr_standard","I19";
;
CDS_LIB"mstr_standard"
BODY_TYPE"PLUMBING"
HDL_TAP"TRUE";
"B \NAC \NWC"12;
"S \NAC"
BN"6"27;
%"TAP"
"6","(-5575,1400)","0","mstr_standard","I20";
;
CDS_LIB"mstr_standard"
BODY_TYPE"PLUMBING"
HDL_TAP"TRUE";
"B \NAC \NWC"12;
"S \NAC"
BN"7"28;
%"TAP"
"6","(-5575,1500)","0","mstr_standard","I21";
;
CDS_LIB"mstr_standard"
BODY_TYPE"PLUMBING"
HDL_TAP"TRUE";
"B \NAC \NWC"9;
"S \NAC"
BN"0"29;
%"TAP"
"6","(-5575,1550)","0","mstr_standard","I22";
;
CDS_LIB"mstr_standard"
BODY_TYPE"PLUMBING"
HDL_TAP"TRUE";
"B \NAC \NWC"9;
"S \NAC"
BN"1"30;
%"TAP"
"6","(-5575,1600)","0","mstr_standard","I23";
;
CDS_LIB"mstr_standard"
BODY_TYPE"PLUMBING"
HDL_TAP"TRUE";
"B \NAC \NWC"9;
"S \NAC"
BN"2"31;
%"TAP"
"6","(-5575,1650)","0","mstr_standard","I24";
;
CDS_LIB"mstr_standard"
BODY_TYPE"PLUMBING"
HDL_TAP"TRUE";
"B \NAC \NWC"9;
"S \NAC"
BN"3"32;
%"TAP"
"6","(-5575,1700)","0","mstr_standard","I25";
;
CDS_LIB"mstr_standard"
BODY_TYPE"PLUMBING"
HDL_TAP"TRUE";
"B \NAC \NWC"9;
"S \NAC"
BN"4"33;
%"TAP"
"6","(-5575,1750)","0","mstr_standard","I26";
;
CDS_LIB"mstr_standard"
BODY_TYPE"PLUMBING"
HDL_TAP"TRUE";
"B \NAC \NWC"9;
"S \NAC"
BN"5"34;
%"TAP"
"6","(-5575,1800)","0","mstr_standard","I27";
;
CDS_LIB"mstr_standard"
BODY_TYPE"PLUMBING"
HDL_TAP"TRUE";
"B \NAC \NWC"9;
"S \NAC"
BN"6"35;
%"TAP"
"6","(-5575,1900)","0","mstr_standard","I28";
;
CDS_LIB"mstr_standard"
BODY_TYPE"PLUMBING"
HDL_TAP"TRUE";
"B \NAC \NWC"9;
"S \NAC"
BN"8"37;
%"TAP"
"6","(-5575,1850)","0","mstr_standard","I29";
;
CDS_LIB"mstr_standard"
BODY_TYPE"PLUMBING"
HDL_TAP"TRUE";
"B \NAC \NWC"9;
"S \NAC"
BN"7"36;
%"TAP"
"6","(-5575,1950)","0","mstr_standard","I31";
;
CDS_LIB"mstr_standard"
BODY_TYPE"PLUMBING"
HDL_TAP"TRUE";
"B \NAC \NWC"9;
"S \NAC"
BN"9"38;
%"TAP"
"6","(-5575,2000)","0","mstr_standard","I32";
;
CDS_LIB"mstr_standard"
BODY_TYPE"PLUMBING"
HDL_TAP"TRUE";
"B \NAC \NWC"9;
"S \NAC"
BN"10"39;
%"TAP"
"6","(-5575,2050)","0","mstr_standard","I33";
;
CDS_LIB"mstr_standard"
BODY_TYPE"PLUMBING"
HDL_TAP"TRUE";
"B \NAC \NWC"9;
"S \NAC"
BN"11"48;
%"TAP"
"6","(-5575,2100)","0","mstr_standard","I34";
;
CDS_LIB"mstr_standard"
BODY_TYPE"PLUMBING"
HDL_TAP"TRUE";
"B \NAC \NWC"9;
"S \NAC"
BN"12"49;
%"TAP"
"6","(-5575,2150)","0","mstr_standard","I35";
;
CDS_LIB"mstr_standard"
BODY_TYPE"PLUMBING"
HDL_TAP"TRUE";
"B \NAC \NWC"9;
"S \NAC"
BN"13"50;
%"TAP"
"6","(-5575,2200)","0","mstr_standard","I36";
;
CDS_LIB"mstr_standard"
BODY_TYPE"PLUMBING"
HDL_TAP"TRUE";
"B \NAC \NWC"9;
"S \NAC"
BN"14"51;
%"TAP"
"6","(-5575,2250)","0","mstr_standard","I37";
;
CDS_LIB"mstr_standard"
BODY_TYPE"PLUMBING"
HDL_TAP"TRUE";
"B \NAC \NWC"9;
"S \NAC"
BN"15"52;
%"TAP"
"6","(-5575,2300)","0","mstr_standard","I38";
;
CDS_LIB"mstr_standard"
BODY_TYPE"PLUMBING"
HDL_TAP"TRUE";
"B \NAC \NWC"9;
"S \NAC"
BN"16"53;
%"TAP"
"6","(-5575,2350)","0","mstr_standard","I39";
;
CDS_LIB"mstr_standard"
BODY_TYPE"PLUMBING"
HDL_TAP"TRUE";
"B \NAC \NWC"9;
"S \NAC"
BN"17"54;
%"TAP"
"6","(-5575,2400)","0","mstr_standard","I40";
;
CDS_LIB"mstr_standard"
BODY_TYPE"PLUMBING"
HDL_TAP"TRUE";
"B \NAC \NWC"9;
"S \NAC"
BN"18"55;
%"TAP"
"6","(-5575,2450)","0","mstr_standard","I41";
;
CDS_LIB"mstr_standard"
BODY_TYPE"PLUMBING"
HDL_TAP"TRUE";
"B \NAC \NWC"9;
"S \NAC"
BN"19"56;
%"TAP"
"6","(-5575,2500)","0","mstr_standard","I42";
;
CDS_LIB"mstr_standard"
BODY_TYPE"PLUMBING"
HDL_TAP"TRUE";
"B \NAC \NWC"9;
"S \NAC"
BN"20"57;
%"TAP"
"6","(-5575,2550)","0","mstr_standard","I43";
;
CDS_LIB"mstr_standard"
BODY_TYPE"PLUMBING"
HDL_TAP"TRUE";
"B \NAC \NWC"9;
"S \NAC"
BN"21"58;
%"TAP"
"6","(-5575,2600)","0","mstr_standard","I44";
;
CDS_LIB"mstr_standard"
BODY_TYPE"PLUMBING"
HDL_TAP"TRUE";
"B \NAC \NWC"9;
"S \NAC"
BN"22"59;
%"TAP"
"6","(-5575,2650)","0","mstr_standard","I45";
;
CDS_LIB"mstr_standard"
BODY_TYPE"PLUMBING"
HDL_TAP"TRUE";
"B \NAC \NWC"9;
"S \NAC"
BN"23"60;
%"TAP"
"6","(-5575,2700)","0","mstr_standard","I46";
;
CDS_LIB"mstr_standard"
BODY_TYPE"PLUMBING"
HDL_TAP"TRUE";
"B \NAC \NWC"9;
"S \NAC"
BN"24"61;
%"TAP"
"6","(-5575,2800)","0","mstr_standard","I47";
;
CDS_LIB"mstr_standard"
BODY_TYPE"PLUMBING"
HDL_TAP"TRUE";
"B \NAC \NWC"9;
"S \NAC"
BN"26"63;
%"TAP"
"6","(-5575,2750)","0","mstr_standard","I48";
;
CDS_LIB"mstr_standard"
BODY_TYPE"PLUMBING"
HDL_TAP"TRUE";
"B \NAC \NWC"9;
"S \NAC"
BN"25"62;
%"TAP"
"6","(-5575,2850)","0","mstr_standard","I49";
;
CDS_LIB"mstr_standard"
BODY_TYPE"PLUMBING"
HDL_TAP"TRUE";
"B \NAC \NWC"9;
"S \NAC"
BN"27"64;
%"TAP"
"6","(-5575,600)","0","mstr_standard","I5";
;
CDS_LIB"mstr_standard"
BODY_TYPE"PLUMBING"
HDL_TAP"TRUE";
"B \NAC \NWC"10;
"S \NAC"
BN"0"44;
%"TAP"
"6","(-5575,2900)","0","mstr_standard","I50";
;
CDS_LIB"mstr_standard"
BODY_TYPE"PLUMBING"
HDL_TAP"TRUE";
"B \NAC \NWC"9;
"S \NAC"
BN"28"65;
%"TAP"
"6","(-5575,2950)","0","mstr_standard","I51";
;
CDS_LIB"mstr_standard"
BODY_TYPE"PLUMBING"
HDL_TAP"TRUE";
"B \NAC \NWC"9;
"S \NAC"
BN"29"66;
%"TAP"
"6","(-5575,3050)","0","mstr_standard","I52";
;
CDS_LIB"mstr_standard"
BODY_TYPE"PLUMBING"
HDL_TAP"TRUE";
"B \NAC \NWC"9;
"S \NAC"
BN"31"68;
%"TAP"
"6","(-5575,3000)","0","mstr_standard","I53";
;
CDS_LIB"mstr_standard"
BODY_TYPE"PLUMBING"
HDL_TAP"TRUE";
"B \NAC \NWC"9;
"S \NAC"
BN"30"67;
%"TAP"
"6","(-5575,3100)","0","mstr_standard","I54";
;
CDS_LIB"mstr_standard"
BODY_TYPE"PLUMBING"
HDL_TAP"TRUE";
"B \NAC \NWC"9;
"S \NAC"
BN"32"69;
%"TAP"
"6","(-5575,3150)","0","mstr_standard","I55";
;
CDS_LIB"mstr_standard"
BODY_TYPE"PLUMBING"
HDL_TAP"TRUE";
"B \NAC \NWC"9;
"S \NAC"
BN"33"19;
%"TAP"
"6","(-5575,3200)","0","mstr_standard","I56";
;
CDS_LIB"mstr_standard"
BODY_TYPE"PLUMBING"
HDL_TAP"TRUE";
"B \NAC \NWC"9;
"S \NAC"
BN"34"70;
%"TAP"
"6","(-5575,3300)","0","mstr_standard","I57";
;
CDS_LIB"mstr_standard"
BODY_TYPE"PLUMBING"
HDL_TAP"TRUE";
"B \NAC \NWC"9;
"S \NAC"
BN"36"71;
%"TAP"
"6","(-5575,3250)","0","mstr_standard","I58";
;
CDS_LIB"mstr_standard"
BODY_TYPE"PLUMBING"
HDL_TAP"TRUE";
"B \NAC \NWC"9;
"S \NAC"
BN"35"18;
%"TAP"
"6","(-5575,3350)","0","mstr_standard","I59";
;
CDS_LIB"mstr_standard"
BODY_TYPE"PLUMBING"
HDL_TAP"TRUE";
"B \NAC \NWC"9;
"S \NAC"
BN"37"72;
%"TAP"
"6","(-5575,650)","0","mstr_standard","I6";
;
CDS_LIB"mstr_standard"
BODY_TYPE"PLUMBING"
HDL_TAP"TRUE";
"B \NAC \NWC"10;
"S \NAC"
BN"1"45;
%"TAP"
"6","(-5575,3400)","0","mstr_standard","I60";
;
CDS_LIB"mstr_standard"
BODY_TYPE"PLUMBING"
HDL_TAP"TRUE";
"B \NAC \NWC"9;
"S \NAC"
BN"38"73;
%"TAP"
"6","(-5575,3450)","0","mstr_standard","I61";
;
CDS_LIB"mstr_standard"
BODY_TYPE"PLUMBING"
HDL_TAP"TRUE";
"B \NAC \NWC"9;
"S \NAC"
BN"39"74;
%"TAP"
"6","(-5575,3500)","0","mstr_standard","I62";
;
CDS_LIB"mstr_standard"
BODY_TYPE"PLUMBING"
HDL_TAP"TRUE";
"B \NAC \NWC"9;
"S \NAC"
BN"40"75;
%"TAP"
"6","(-5575,3550)","0","mstr_standard","I63";
;
CDS_LIB"mstr_standard"
BODY_TYPE"PLUMBING"
HDL_TAP"TRUE";
"B \NAC \NWC"9;
"S \NAC"
BN"41"15;
%"TAP"
"6","(-5575,3600)","0","mstr_standard","I64";
;
CDS_LIB"mstr_standard"
BODY_TYPE"PLUMBING"
HDL_TAP"TRUE";
"B \NAC \NWC"9;
"S \NAC"
BN"42"76;
%"TAP"
"6","(-5575,3650)","0","mstr_standard","I65";
;
CDS_LIB"mstr_standard"
BODY_TYPE"PLUMBING"
HDL_TAP"TRUE";
"B \NAC \NWC"9;
"S \NAC"
BN"43"77;
%"TAP"
"6","(-5575,3700)","0","mstr_standard","I66";
;
CDS_LIB"mstr_standard"
BODY_TYPE"PLUMBING"
HDL_TAP"TRUE";
"B \NAC \NWC"9;
"S \NAC"
BN"44"78;
%"TAP"
"6","(-5575,3750)","0","mstr_standard","I67";
;
CDS_LIB"mstr_standard"
BODY_TYPE"PLUMBING"
HDL_TAP"TRUE";
"B \NAC \NWC"9;
"S \NAC"
BN"45"79;
%"TAP"
"6","(-5575,3800)","0","mstr_standard","I68";
;
CDS_LIB"mstr_standard"
BODY_TYPE"PLUMBING"
HDL_TAP"TRUE";
"B \NAC \NWC"9;
"S \NAC"
BN"46"80;
%"TAP"
"6","(-5575,3850)","0","mstr_standard","I69";
;
CDS_LIB"mstr_standard"
BODY_TYPE"PLUMBING"
HDL_TAP"TRUE";
"B \NAC \NWC"9;
"S \NAC"
BN"47"81;
%"TAP"
"6","(-5575,750)","0","mstr_standard","I7";
;
CDS_LIB"mstr_standard"
BODY_TYPE"PLUMBING"
HDL_TAP"TRUE";
"B \NAC \NWC"10;
"S \NAC"
BN"3"47;
%"TAP"
"6","(-5575,3900)","0","mstr_standard","I70";
;
CDS_LIB"mstr_standard"
BODY_TYPE"PLUMBING"
HDL_TAP"TRUE";
"B \NAC \NWC"9;
"S \NAC"
BN"48"82;
%"TAP"
"6","(-5575,3950)","0","mstr_standard","I71";
;
CDS_LIB"mstr_standard"
BODY_TYPE"PLUMBING"
HDL_TAP"TRUE";
"B \NAC \NWC"9;
"S \NAC"
BN"49"83;
%"TAP"
"6","(-5575,4000)","0","mstr_standard","I73";
;
CDS_LIB"mstr_standard"
BODY_TYPE"PLUMBING"
HDL_TAP"TRUE";
"B \NAC \NWC"9;
"S \NAC"
BN"50"84;
%"TAP"
"6","(-5575,4050)","0","mstr_standard","I74";
;
CDS_LIB"mstr_standard"
BODY_TYPE"PLUMBING"
HDL_TAP"TRUE";
"B \NAC \NWC"9;
"S \NAC"
BN"51"85;
%"TAP"
"6","(-5575,4100)","0","mstr_standard","I75";
;
CDS_LIB"mstr_standard"
BODY_TYPE"PLUMBING"
HDL_TAP"TRUE";
"B \NAC \NWC"9;
"S \NAC"
BN"52"86;
%"TAP"
"6","(-5575,4150)","0","mstr_standard","I76";
;
CDS_LIB"mstr_standard"
BODY_TYPE"PLUMBING"
HDL_TAP"TRUE";
"B \NAC \NWC"9;
"S \NAC"
BN"53"16;
%"TAP"
"6","(-5575,4200)","0","mstr_standard","I77";
;
CDS_LIB"mstr_standard"
BODY_TYPE"PLUMBING"
HDL_TAP"TRUE";
"B \NAC \NWC"9;
"S \NAC"
BN"54"87;
%"TAP"
"6","(-5575,4250)","0","mstr_standard","I78";
;
CDS_LIB"mstr_standard"
BODY_TYPE"PLUMBING"
HDL_TAP"TRUE";
"B \NAC \NWC"9;
"S \NAC"
BN"55"14;
%"TAP"
"6","(-5575,4300)","0","mstr_standard","I79";
;
CDS_LIB"mstr_standard"
BODY_TYPE"PLUMBING"
HDL_TAP"TRUE";
"B \NAC \NWC"9;
"S \NAC"
BN"56"88;
%"TAP"
"6","(-5575,700)","0","mstr_standard","I8";
;
CDS_LIB"mstr_standard"
BODY_TYPE"PLUMBING"
HDL_TAP"TRUE";
"B \NAC \NWC"10;
"S \NAC"
BN"2"46;
%"TAP"
"6","(-5575,4350)","0","mstr_standard","I80";
;
CDS_LIB"mstr_standard"
BODY_TYPE"PLUMBING"
HDL_TAP"TRUE";
"B \NAC \NWC"9;
"S \NAC"
BN"57"89;
%"TAP"
"6","(-5575,4400)","0","mstr_standard","I81";
;
CDS_LIB"mstr_standard"
BODY_TYPE"PLUMBING"
HDL_TAP"TRUE";
"B \NAC \NWC"9;
"S \NAC"
BN"58"90;
%"TAP"
"6","(-5575,4450)","0","mstr_standard","I82";
;
CDS_LIB"mstr_standard"
BODY_TYPE"PLUMBING"
HDL_TAP"TRUE";
"B \NAC \NWC"9;
"S \NAC"
BN"59"91;
%"TAP"
"6","(-5575,4500)","0","mstr_standard","I83";
;
CDS_LIB"mstr_standard"
BODY_TYPE"PLUMBING"
HDL_TAP"TRUE";
"B \NAC \NWC"9;
"S \NAC"
BN"60"92;
%"TAP"
"6","(-5575,4550)","0","mstr_standard","I84";
;
CDS_LIB"mstr_standard"
BODY_TYPE"PLUMBING"
HDL_TAP"TRUE";
"B \NAC \NWC"9;
"S \NAC"
BN"61"93;
%"TAP"
"6","(-5575,4600)","0","mstr_standard","I85";
;
CDS_LIB"mstr_standard"
BODY_TYPE"PLUMBING"
HDL_TAP"TRUE";
"B \NAC \NWC"9;
"S \NAC"
BN"62"94;
%"TAP"
"6","(-5575,4650)","0","mstr_standard","I86";
;
CDS_LIB"mstr_standard"
BODY_TYPE"PLUMBING"
HDL_TAP"TRUE";
"B \NAC \NWC"9;
"S \NAC"
BN"63"95;
%"TAP"
"6","(-2850,750)","2","mstr_standard","I87";
;
CDS_LIB"mstr_standard"
BODY_TYPE"PLUMBING"
HDL_TAP"TRUE";
"B \NAC \NWC"4;
"S \NAC"
BN"1"117;
%"TAP"
"6","(-2850,700)","2","mstr_standard","I88";
;
CDS_LIB"mstr_standard"
BODY_TYPE"PLUMBING"
HDL_TAP"TRUE";
"B \NAC \NWC"4;
"S \NAC"
BN"0"116;
%"TAP"
"6","(-2850,800)","2","mstr_standard","I89";
;
CDS_LIB"mstr_standard"
BODY_TYPE"PLUMBING"
HDL_TAP"TRUE";
"B \NAC \NWC"5;
"S \NAC"
BN"0"114;
%"TAP"
"6","(-5575,850)","0","mstr_standard","I9";
;
CDS_LIB"mstr_standard"
BODY_TYPE"PLUMBING"
HDL_TAP"TRUE";
"B \NAC \NWC"11;
"S \NAC"
BN"1"41;
%"TAP"
"6","(-2850,850)","2","mstr_standard","I90";
;
CDS_LIB"mstr_standard"
BODY_TYPE"PLUMBING"
HDL_TAP"TRUE";
"B \NAC \NWC"5;
"S \NAC"
BN"1"115;
%"TAP"
"6","(-2850,1050)","2","mstr_standard","I91";
;
CDS_LIB"mstr_standard"
BODY_TYPE"PLUMBING"
HDL_TAP"TRUE";
"B \NAC \NWC"7;
"S \NAC"
BN"2"104;
%"TAP"
"6","(-2850,1000)","2","mstr_standard","I92";
;
CDS_LIB"mstr_standard"
BODY_TYPE"PLUMBING"
HDL_TAP"TRUE";
"B \NAC \NWC"7;
"S \NAC"
BN"1"103;
%"TAP"
"6","(-2850,950)","2","mstr_standard","I93";
;
CDS_LIB"mstr_standard"
BODY_TYPE"PLUMBING"
HDL_TAP"TRUE";
"B \NAC \NWC"7;
"S \NAC"
BN"0"102;
%"TAP"
"6","(-2850,1150)","2","mstr_standard","I94";
;
CDS_LIB"mstr_standard"
BODY_TYPE"PLUMBING"
HDL_TAP"TRUE";
"B \NAC \NWC"7;
"S \NAC"
BN"4"106;
%"TAP"
"6","(-2850,1100)","2","mstr_standard","I95";
;
CDS_LIB"mstr_standard"
BODY_TYPE"PLUMBING"
HDL_TAP"TRUE";
"B \NAC \NWC"7;
"S \NAC"
BN"3"105;
%"TAP"
"6","(-2850,1200)","2","mstr_standard","I96";
;
CDS_LIB"mstr_standard"
BODY_TYPE"PLUMBING"
HDL_TAP"TRUE";
"B \NAC \NWC"7;
"S \NAC"
BN"5"107;
%"TAP"
"6","(-2850,1250)","2","mstr_standard","I97";
;
CDS_LIB"mstr_standard"
BODY_TYPE"PLUMBING"
HDL_TAP"TRUE";
"B \NAC \NWC"7;
"S \NAC"
BN"6"108;
%"TAP"
"6","(-2850,1300)","2","mstr_standard","I98";
;
CDS_LIB"mstr_standard"
BODY_TYPE"PLUMBING"
HDL_TAP"TRUE";
"B \NAC \NWC"7;
"S \NAC"
BN"7"109;
%"TAP"
"6","(-2850,1400)","2","mstr_standard","I99";
;
CDS_LIB"mstr_standard"
BODY_TYPE"PLUMBING"
HDL_TAP"TRUE";
"B \NAC \NWC"8;
"S \NAC"
BN"0"96;
END.
